# S9S_MB_2U (Grand Teton) — schematic netlist excerpt (pin names and nets, part order shuffled) for the footprints in the layout excerpt that follows; sources: Cadence DE-HDL packaged netlist, KiCad conversion of 03242023_DA0F0TMBIJ0_F0T_Motherboard_J_brd_V01_OCP.brd

R4731  Q_RES  100K 1% EMPTY  pkg 0402LF  page 144 : A = PRSNT_CABLE_SWB_B2_N ; B = GND
PC1341  Q_CAP  0.1UF 25V 10% X7R  pkg 0402  page 268 : A = GND ; B = PVCCIN_CPU0_VREF

(kicad_pcb
	(version 20260206)
	(generator "pcbnew")
	(generator_version "10.0")
	(general
		(thickness 1.6)
		(legacy_teardrops no)
	)
	(paper "A4")
	(title_block
		(title "03242023_DA0F0TMBIJ0_F0T_Motherboard_J_brd_V01_OCP.brd")
		(comment 1 "Grand Teton / footprints 3006-3007 of 6105")
	)
	(layers
		(0 "F.Cu" signal "TOP")
		(4 "In1.Cu" signal "GND")
		(6 "In2.Cu" signal "IN1")
		(8 "In3.Cu" signal "GND1")
		(10 "In4.Cu" signal "IN2")
		(12 "In5.Cu" signal "GND2")
		(14 "In6.Cu" signal "IN3")
		(16 "In7.Cu" signal "GND3")
		(18 "In8.Cu" signal "VCC")
		(20 "In9.Cu" signal "VCC1")
		(22 "In10.Cu" signal "GND4")
		(24 "In11.Cu" signal "IN4")
		(26 "In12.Cu" signal "GND5")
		(28 "In13.Cu" signal "IN5")
		(30 "In14.Cu" signal "GND6")
		(32 "In15.Cu" signal "IN6")
		(34 "In16.Cu" signal "GND7")
		(2 "B.Cu" signal "BOTTOM")
		(9 "F.Adhes" user "F.Adhesive")
		(11 "B.Adhes" user "B.Adhesive")
		(13 "F.Paste" user "Package Geometry/Pastemask Top")
		(15 "B.Paste" user "Package Geometry/Pastemask Bottom")
		(5 "F.SilkS" user "Ref Des/Silkscreen Top")
		(7 "B.SilkS" user "Ref Des/Silkscreen Bottom")
		(1 "F.Mask" user "Board Geometry/Soldermask Top")
		(3 "B.Mask" user "Board Geometry/Soldermask Bottom")
		(17 "Dwgs.User" user "User.Drawings")
		(19 "Cmts.User" user "User.Comments")
		(21 "Eco1.User" user "User.Eco1")
		(23 "Eco2.User" user "User.Eco2")
		(25 "Edge.Cuts" user "Board Geometry/Outline")
		(27 "Margin" user)
		(31 "F.CrtYd" user "Package Geometry/Place Bound Top")
		(29 "B.CrtYd" user "Package Geometry/Place Bound Bottom")
		(35 "F.Fab" user "Ref Des/Assembly Top")
		(33 "B.Fab" user "Ref Des/Assembly Bottom")
	)
	(footprint ""
		(layer "F.Cu")
		(at 358.425496 -338.298028 -90)
		(property "Reference" "PC1341"
			(at 0 0 270)
			(layer "F.SilkS")
			(hide yes)
			(effects
				(font
					(size 1.27 1.27)
				)
			)
		)
		(property "Value" ""
			(at 0 0 270)
			(layer "F.Fab")
			(effects
				(font
					(size 1.27 1.27)
				)
			)
		)
		(duplicate_pad_numbers_are_jumpers no)
		(fp_line
			(start -0.7874 0.4064)
			(end -0.7874 -0.4064)
			(stroke
				(width 0.1524)
				(type default)
			)
			(layer "F.SilkS")
		)
		(fp_line
			(start 0.7874 0.4064)
			(end -0.7874 0.4064)
			(stroke
				(width 0.1524)
				(type default)
			)
			(layer "F.SilkS")
		)
		(fp_line
			(start -0.7874 -0.4064)
			(end 0.7874 -0.4064)
			(stroke
				(width 0.1524)
				(type default)
			)
			(layer "F.SilkS")
		)
		(fp_line
			(start 0.7874 -0.4064)
			(end 0.7874 0.4064)
			(stroke
				(width 0.1524)
				(type default)
			)
			(layer "F.SilkS")
		)
		(fp_line
			(start -0.67945 0.3048)
			(end -0.67945 -0.305054)
			(stroke
				(width 0.1)
				(type default)
			)
			(layer "F.Fab")
		)
		(fp_line
			(start -0.12065 0.3048)
			(end -0.67945 0.3048)
			(stroke
				(width 0.1)
				(type default)
			)
			(layer "F.Fab")
		)
		(fp_line
			(start 0.120396 0.3048)
			(end 0.120396 0.2794)
			(stroke
				(width 0.1)
				(type default)
			)
			(layer "F.Fab")
		)
		(fp_line
			(start 0.67945 0.3048)
			(end 0.120396 0.3048)
			(stroke
				(width 0.1)
				(type default)
			)
			(layer "F.Fab")
		)
		(fp_line
			(start -0.12065 0.2794)
			(end -0.12065 0.3048)
			(stroke
				(width 0.1)
				(type default)
			)
			(layer "F.Fab")
		)
		(fp_line
			(start 0.120396 0.2794)
			(end -0.12065 0.2794)
			(stroke
				(width 0.1)
				(type default)
			)
			(layer "F.Fab")
		)
		(fp_line
			(start -0.12065 -0.2794)
			(end 0.12065 -0.2794)
			(stroke
				(width 0.1)
				(type default)
			)
			(layer "F.Fab")
		)
		(fp_line
			(start 0.12065 -0.2794)
			(end 0.12065 -0.3048)
			(stroke
				(width 0.1)
				(type default)
			)
			(layer "F.Fab")
		)
		(fp_line
			(start 0.12065 -0.3048)
			(end 0.67945 -0.3048)
			(stroke
				(width 0.1)
				(type default)
			)
			(layer "F.Fab")
		)
		(fp_line
			(start 0.67945 -0.3048)
			(end 0.67945 0.3048)
			(stroke
				(width 0.1)
				(type default)
			)
			(layer "F.Fab")
		)
		(fp_line
			(start -0.67945 -0.305054)
			(end -0.12065 -0.305054)
			(stroke
				(width 0.1)
				(type default)
			)
			(layer "F.Fab")
		)
		(fp_line
			(start -0.12065 -0.305054)
			(end -0.12065 -0.2794)
			(stroke
				(width 0.1)
				(type default)
			)
			(layer "F.Fab")
		)
		(pad "1" smd circle
			(at -0.40005 0 270)
			(size 0 0)
			(layers "F.Cu" "F.Mask" "F.Paste")
			(net "GND")
		)
		(pad "2" smd circle
			(at 0.40005 0 270)
			(size 0 0)
			(layers "F.Cu" "F.Mask" "F.Paste")
			(net "PVCCIN_CPU0_VREF")
		)
	)
	(footprint ""
		(layer "F.Cu")
		(at 355.8286 -404.876 180)
		(property "Reference" "R4731"
			(at 0 0 180)
			(layer "F.SilkS")
			(hide yes)
			(effects
				(font
					(size 1.27 1.27)
				)
			)
		)
		(property "Value" ""
			(at 0 0 180)
			(layer "F.Fab")
			(effects
				(font
					(size 1.27 1.27)
				)
			)
		)
		(duplicate_pad_numbers_are_jumpers no)
		(fp_line
			(start 0.7874 0.4064)
			(end -0.7874 0.4064)
			(stroke
				(width 0.1524)
				(type default)
			)
			(layer "F.SilkS")
		)
		(fp_line
			(start 0.7874 -0.4064)
			(end 0.7874 0.4064)
			(stroke
				(width 0.1524)
				(type default)
			)
			(layer "F.SilkS")
		)
		(fp_line
			(start -0.7874 0.4064)
			(end -0.7874 -0.4064)
			(stroke
				(width 0.1524)
				(type default)
			)
			(layer "F.SilkS")
		)
		(fp_line
			(start -0.7874 -0.4064)
			(end 0.7874 -0.4064)
			(stroke
				(width 0.1524)
				(type default)
			)
			(layer "F.SilkS")
		)
		(fp_line
			(start 0.67945 0.3048)
			(end 0.120396 0.3048)
			(stroke
				(width 0.1)
				(type default)
			)
			(layer "F.Fab")
		)
		(fp_line
			(start 0.67945 -0.3048)
			(end 0.67945 0.3048)
			(stroke
				(width 0.1)
				(type default)
			)
			(layer "F.Fab")
		)
		(fp_line
			(start 0.12065 -0.2794)
			(end 0.12065 -0.3048)
			(stroke
				(width 0.1)
				(type default)
			)
			(layer "F.Fab")
		)
		(fp_line
			(start 0.12065 -0.3048)
			(end 0.67945 -0.3048)
			(stroke
				(width 0.1)
				(type default)
			)
			(layer "F.Fab")
		)
		(fp_line
			(start 0.120396 0.3048)
			(end 0.120396 0.2794)
			(stroke
				(width 0.1)
				(type default)
			)
			(layer "F.Fab")
		)
		(fp_line
			(start 0.120396 0.2794)
			(end -0.12065 0.2794)
			(stroke
				(width 0.1)
				(type default)
			)
			(layer "F.Fab")
		)
		(fp_line
			(start -0.12065 0.3048)
			(end -0.67945 0.3048)
			(stroke
				(width 0.1)
				(type default)
			)
			(layer "F.Fab")
		)
		(fp_line
			(start -0.12065 0.2794)
			(end -0.12065 0.3048)
			(stroke
				(width 0.1)
				(type default)
			)
			(layer "F.Fab")
		)
		(fp_line
			(start -0.12065 -0.2794)
			(end 0.12065 -0.2794)
			(stroke
				(width 0.1)
				(type default)
			)
			(layer "F.Fab")
		)
		(fp_line
			(start -0.12065 -0.305054)
			(end -0.12065 -0.2794)
			(stroke
				(width 0.1)
				(type default)
			)
			(layer "F.Fab")
		)
		(fp_line
			(start -0.67945 0.3048)
			(end -0.67945 -0.305054)
			(stroke
				(width 0.1)
				(type default)
			)
			(layer "F.Fab")
		)
		(fp_line
			(start -0.67945 -0.305054)
			(end -0.12065 -0.305054)
			(stroke
				(width 0.1)
				(type default)
			)
			(layer "F.Fab")
		)
		(pad "1" smd circle
			(at -0.40005 0 180)
			(size 0 0)
			(layers "F.Cu" "F.Mask" "F.Paste")
			(net "PRSNT_CABLE_SWB_B2_N")
		)
		(pad "2" smd circle
			(at 0.40005 0 180)
			(size 0 0)
			(layers "F.Cu" "F.Mask" "F.Paste")
			(net "GND")
		)
	)
)
